(kicad_pcb
	(version 20260206)
	(generator "pcbnew")
	(generator_version "10.0")
	(general
		(thickness 1.6)
		(legacy_teardrops no)
	)
	(paper "A4")
	(title_block
		(title "Bryce Canyon_R.DPB_16317-1_OCP.brd")
		(comment 1 "Bryce Canyon / footprints 1426-1432 of 2099")
	)
	(layers
		(0 "F.Cu" signal "TOP")
		(4 "In1.Cu" signal "L2GND")
		(6 "In2.Cu" signal "L3")
		(8 "In3.Cu" signal "L4VCC")
		(10 "In4.Cu" signal "L5VCC")
		(12 "In5.Cu" signal "L6")
		(14 "In6.Cu" signal "L7GND")
		(2 "B.Cu" signal "BOTTOM")
		(9 "F.Adhes" user "F.Adhesive")
		(11 "B.Adhes" user "B.Adhesive")
		(13 "F.Paste" user "Package Geometry/Pastemask Top")
		(15 "B.Paste" user "Package Geometry/Pastemask Bottom")
		(5 "F.SilkS" user "Ref Des/Silkscreen Top")
		(7 "B.SilkS" user "Ref Des/Silkscreen Bottom")
		(1 "F.Mask" user "Board Geometry/Soldermask Top")
		(3 "B.Mask" user "Board Geometry/Soldermask Bottom")
		(17 "Dwgs.User" user "User.Drawings")
		(19 "Cmts.User" user "User.Comments")
		(21 "Eco1.User" user "User.Eco1")
		(23 "Eco2.User" user "User.Eco2")
		(25 "Edge.Cuts" user "Board Geometry/Outline")
		(27 "Margin" user)
		(31 "F.CrtYd" user "Package Geometry/Place Bound Top")
		(29 "B.CrtYd" user "Package Geometry/Place Bound Bottom")
		(35 "F.Fab" user "Ref Des/Assembly Top")
		(33 "B.Fab" user "Ref Des/Assembly Bottom")
	)
	(footprint ""
		(layer "F.Cu")
		(at 85.471 -246.2276 -90)
		(property "Reference" "R198"
			(at 0 0 270)
			(layer "F.SilkS")
			(hide yes)
			(effects
				(font
					(size 1.27 1.27)
				)
			)
		)
		(property "Value" "0R2J-2-GP"
			(at 0.064008 -3.993896 270)
			(unlocked yes)
			(layer "F.Fab")
			(hide yes)
			(effects
				(font
					(size 1.016 1.016)
					(thickness 0.1524)
				)
			)
		)
		(property "Device Type" "R402H16"
			(at 0.064008 -5.517896 270)
			(unlocked yes)
			(layer "F.Fab")
			(hide yes)
			(effects
				(font
					(size 1.016 1.016)
					(thickness 0.1524)
				)
			)
		)
		(duplicate_pad_numbers_are_jumpers no)
		(fp_line
			(start -0.508 -0.9398)
			(end -0.508 0.9398)
			(stroke
				(width 0.1524)
				(type default)
			)
			(layer "F.SilkS")
		)
		(fp_line
			(start 0.508 -0.9398)
			(end -0.508 -0.9398)
			(stroke
				(width 0.1524)
				(type default)
			)
			(layer "F.SilkS")
		)
		(fp_rect
			(start -0.508 0.9398)
			(end 0.508 -0.9398)
			(stroke
				(width 0)
				(type default)
			)
			(fill no)
			(layer "F.CrtYd")
		)
		(fp_rect
			(start -0.508 0.9398)
			(end 0.508 -0.9398)
			(stroke
				(width 0)
				(type default)
			)
			(fill no)
			(layer "F.Fab")
		)
		(pad "1" smd custom
			(at 0 -0.4445 270)
			(size 0.1397 0.1397)
			(layers "F.Cu" "F.Mask" "F.Paste")
			(net "DRIVE_B_2_PWR")
			(options
				(clearance outline)
				(anchor circle)
			)
			(primitives
				(gr_poly
					(pts
						(arc
							(start -0.1778 -0.2794)
							(mid -0.249642 -0.249642)
							(end -0.2794 -0.1778)
						)
						(arc
							(start -0.2794 0.1778)
							(mid -0.249642 0.249642)
							(end -0.1778 0.2794)
						)
						(arc
							(start 0.1778 0.2794)
							(mid 0.249642 0.249642)
							(end 0.2794 0.1778)
						)
						(arc
							(start 0.2794 -0.1778)
							(mid 0.249642 -0.249642)
							(end 0.1778 -0.2794)
						)
					)
					(width 0)
					(fill yes)
				)
			)
		)
		(pad "2" smd custom
			(at 0 0.4445 270)
			(size 0.1397 0.1397)
			(layers "F.Cu" "F.Mask" "F.Paste")
			(net "SW_PWR_R_HDD2")
			(options
				(clearance outline)
				(anchor circle)
			)
			(primitives
				(gr_poly
					(pts
						(arc
							(start -0.1778 -0.2794)
							(mid -0.249642 -0.249642)
							(end -0.2794 -0.1778)
						)
						(arc
							(start -0.2794 0.1778)
							(mid -0.249642 0.249642)
							(end -0.1778 0.2794)
						)
						(arc
							(start 0.1778 0.2794)
							(mid 0.249642 0.249642)
							(end 0.2794 0.1778)
						)
						(arc
							(start 0.2794 -0.1778)
							(mid 0.249642 -0.249642)
							(end 0.1778 -0.2794)
						)
					)
					(width 0)
					(fill yes)
				)
			)
		)
	)
	(footprint ""
		(layer "F.Cu")
		(at 403.351746 -212.390228 -90)
		(property "Reference" "R293"
			(at 0 0 270)
			(layer "F.SilkS")
			(hide yes)
			(effects
				(font
					(size 1.27 1.27)
				)
			)
		)
		(property "Value" "4K7R2F-GP"
			(at 0.064008 -3.993896 270)
			(unlocked yes)
			(layer "F.Fab")
			(hide yes)
			(effects
				(font
					(size 1.016 1.016)
					(thickness 0.1524)
				)
			)
		)
		(property "Device Type" "R402H16"
			(at 0.064008 -5.517896 270)
			(unlocked yes)
			(layer "F.Fab")
			(hide yes)
			(effects
				(font
					(size 1.016 1.016)
					(thickness 0.1524)
				)
			)
		)
		(duplicate_pad_numbers_are_jumpers no)
		(fp_line
			(start -0.508 -0.9398)
			(end -0.508 0.9398)
			(stroke
				(width 0.1524)
				(type default)
			)
			(layer "F.SilkS")
		)
		(fp_line
			(start 0.508 -0.9398)
			(end -0.508 -0.9398)
			(stroke
				(width 0.1524)
				(type default)
			)
			(layer "F.SilkS")
		)
		(fp_rect
			(start -0.508 0.9398)
			(end 0.508 -0.9398)
			(stroke
				(width 0)
				(type default)
			)
			(fill no)
			(layer "F.CrtYd")
		)
		(fp_rect
			(start -0.508 0.9398)
			(end 0.508 -0.9398)
			(stroke
				(width 0)
				(type default)
			)
			(fill no)
			(layer "F.Fab")
		)
		(pad "1" smd custom
			(at 0 -0.4445 270)
			(size 0.1397 0.1397)
			(layers "F.Cu" "F.Mask" "F.Paste")
			(net "DRIVE_B_9_ACT")
			(options
				(clearance outline)
				(anchor circle)
			)
			(primitives
				(gr_poly
					(pts
						(arc
							(start -0.1778 -0.2794)
							(mid -0.249642 -0.249642)
							(end -0.2794 -0.1778)
						)
						(arc
							(start -0.2794 0.1778)
							(mid -0.249642 0.249642)
							(end -0.1778 0.2794)
						)
						(arc
							(start 0.1778 0.2794)
							(mid 0.249642 0.249642)
							(end 0.2794 0.1778)
						)
						(arc
							(start 0.2794 -0.1778)
							(mid 0.249642 -0.249642)
							(end 0.1778 -0.2794)
						)
					)
					(width 0)
					(fill yes)
				)
			)
		)
		(pad "2" smd custom
			(at 0 0.4445 270)
			(size 0.1397 0.1397)
			(layers "F.Cu" "F.Mask" "F.Paste")
			(net "GND")
			(options
				(clearance outline)
				(anchor circle)
			)
			(primitives
				(gr_poly
					(pts
						(arc
							(start -0.1778 -0.2794)
							(mid -0.249642 -0.249642)
							(end -0.2794 -0.1778)
						)
						(arc
							(start -0.2794 0.1778)
							(mid -0.249642 0.249642)
							(end -0.1778 0.2794)
						)
						(arc
							(start 0.1778 0.2794)
							(mid 0.249642 0.249642)
							(end 0.2794 0.1778)
						)
						(arc
							(start 0.2794 -0.1778)
							(mid 0.249642 -0.249642)
							(end 0.1778 -0.2794)
						)
					)
					(width 0)
					(fill yes)
				)
			)
		)
	)
	(footprint ""
		(layer "F.Cu")
		(at 220.853 -226.568 90)
		(property "Reference" "C3"
			(at 0 0 90)
			(layer "F.SilkS")
			(hide yes)
			(effects
				(font
					(size 1.27 1.27)
				)
			)
		)
		(property "Value" "SC1U16V3KX-5GP"
			(at 0 -2.8194 90)
			(unlocked yes)
			(layer "F.Fab")
			(hide yes)
			(effects
				(font
					(size 1.016 1.016)
					(thickness 0.1524)
				)
			)
		)
		(property "Device Type" "C603H36"
			(at 0 -4.3434 90)
			(unlocked yes)
			(layer "F.Fab")
			(hide yes)
			(effects
				(font
					(size 1.016 1.016)
					(thickness 0.1524)
				)
			)
		)
		(duplicate_pad_numbers_are_jumpers no)
		(fp_line
			(start 0.508 0)
			(end -0.508 0)
			(stroke
				(width 0.2032)
				(type default)
			)
			(layer "F.SilkS")
		)
		(fp_rect
			(start -0.5842 1.3335)
			(end 0.5842 -1.3335)
			(stroke
				(width 0)
				(type default)
			)
			(fill no)
			(layer "F.CrtYd")
		)
		(fp_rect
			(start -0.5842 1.3335)
			(end 0.5842 -1.3335)
			(stroke
				(width 0)
				(type default)
			)
			(fill no)
			(layer "F.Fab")
		)
		(pad "1" smd custom
			(at 0 -0.762 90)
			(size 0.2159 0.2159)
			(layers "F.Cu" "F.Mask" "F.Paste")
			(net "P3V3_STBY_B")
			(options
				(clearance outline)
				(anchor circle)
			)
			(primitives
				(gr_poly
					(pts
						(arc
							(start -0.3302 -0.4318)
							(mid -0.402042 -0.402042)
							(end -0.4318 -0.3302)
						)
						(arc
							(start -0.4318 0.3302)
							(mid -0.402042 0.402042)
							(end -0.3302 0.4318)
						)
						(arc
							(start 0.3302 0.4318)
							(mid 0.402042 0.402042)
							(end 0.4318 0.3302)
						)
						(arc
							(start 0.4318 -0.3302)
							(mid 0.402042 -0.402042)
							(end 0.3302 -0.4318)
						)
					)
					(width 0)
					(fill yes)
				)
			)
		)
		(pad "2" smd custom
			(at 0 0.762 90)
			(size 0.2159 0.2159)
			(layers "F.Cu" "F.Mask" "F.Paste")
			(net "GND")
			(options
				(clearance outline)
				(anchor circle)
			)
			(primitives
				(gr_poly
					(pts
						(arc
							(start -0.3302 -0.4318)
							(mid -0.402042 -0.402042)
							(end -0.4318 -0.3302)
						)
						(arc
							(start -0.4318 0.3302)
							(mid -0.402042 0.402042)
							(end -0.3302 0.4318)
						)
						(arc
							(start 0.3302 0.4318)
							(mid 0.402042 0.402042)
							(end 0.4318 0.3302)
						)
						(arc
							(start 0.4318 -0.3302)
							(mid 0.402042 -0.402042)
							(end 0.3302 -0.4318)
						)
					)
					(width 0)
					(fill yes)
				)
			)
		)
	)
	(footprint ""
		(layer "F.Cu")
		(at 426.2882 -134.6454 90)
		(property "Reference" "R560"
			(at 0 0 90)
			(layer "F.SilkS")
			(hide yes)
			(effects
				(font
					(size 1.27 1.27)
				)
			)
		)
		(property "Value" "4K7R2J-2-GP"
			(at 0.064008 -3.993896 90)
			(unlocked yes)
			(layer "F.Fab")
			(hide yes)
			(effects
				(font
					(size 1.016 1.016)
					(thickness 0.1524)
				)
			)
		)
		(property "Device Type" "R402H16"
			(at 0.064008 -5.517896 90)
			(unlocked yes)
			(layer "F.Fab")
			(hide yes)
			(effects
				(font
					(size 1.016 1.016)
					(thickness 0.1524)
				)
			)
		)
		(duplicate_pad_numbers_are_jumpers no)
		(fp_line
			(start 0.508 -0.9398)
			(end -0.508 -0.9398)
			(stroke
				(width 0.1524)
				(type default)
			)
			(layer "F.SilkS")
		)
		(fp_line
			(start -0.508 -0.9398)
			(end -0.508 0.9398)
			(stroke
				(width 0.1524)
				(type default)
			)
			(layer "F.SilkS")
		)
		(fp_rect
			(start -0.508 0.9398)
			(end 0.508 -0.9398)
			(stroke
				(width 0)
				(type default)
			)
			(fill no)
			(layer "F.CrtYd")
		)
		(fp_rect
			(start -0.508 0.9398)
			(end 0.508 -0.9398)
			(stroke
				(width 0)
				(type default)
			)
			(fill no)
			(layer "F.Fab")
		)
		(pad "1" smd custom
			(at 0 -0.4445 90)
			(size 0.1397 0.1397)
			(layers "F.Cu" "F.Mask" "F.Paste")
			(net "P12V_B")
			(options
				(clearance outline)
				(anchor circle)
			)
			(primitives
				(gr_poly
					(pts
						(arc
							(start -0.1778 -0.2794)
							(mid -0.249642 -0.249642)
							(end -0.2794 -0.1778)
						)
						(arc
							(start -0.2794 0.1778)
							(mid -0.249642 0.249642)
							(end -0.1778 0.2794)
						)
						(arc
							(start 0.1778 0.2794)
							(mid 0.249642 0.249642)
							(end 0.2794 0.1778)
						)
						(arc
							(start 0.2794 -0.1778)
							(mid 0.249642 -0.249642)
							(end 0.1778 -0.2794)
						)
					)
					(width 0)
					(fill yes)
				)
			)
		)
		(pad "2" smd custom
			(at 0 0.4445 90)
			(size 0.1397 0.1397)
			(layers "F.Cu" "F.Mask" "F.Paste")
			(net "SW_HDD_P21")
			(options
				(clearance outline)
				(anchor circle)
			)
			(primitives
				(gr_poly
					(pts
						(arc
							(start -0.1778 -0.2794)
							(mid -0.249642 -0.249642)
							(end -0.2794 -0.1778)
						)
						(arc
							(start -0.2794 0.1778)
							(mid -0.249642 0.249642)
							(end -0.1778 0.2794)
						)
						(arc
							(start 0.1778 0.2794)
							(mid 0.249642 0.249642)
							(end 0.2794 0.1778)
						)
						(arc
							(start 0.2794 -0.1778)
							(mid 0.249642 -0.249642)
							(end 0.1778 -0.2794)
						)
					)
					(width 0)
					(fill yes)
				)
			)
		)
	)
	(footprint ""
		(layer "F.Cu")
		(at 191.0588 -146.6342 180)
		(property "Reference" "R461"
			(at 0 0 180)
			(layer "F.SilkS")
			(hide yes)
			(effects
				(font
					(size 1.27 1.27)
				)
			)
		)
		(property "Value" "10KR2F-2-GP"
			(at 0.064008 -3.993896 180)
			(unlocked yes)
			(layer "F.Fab")
			(hide yes)
			(effects
				(font
					(size 1.016 1.016)
					(thickness 0.1524)
				)
			)
		)
		(property "Device Type" "R402H16"
			(at 0.064008 -5.517896 180)
			(unlocked yes)
			(layer "F.Fab")
			(hide yes)
			(effects
				(font
					(size 1.016 1.016)
					(thickness 0.1524)
				)
			)
		)
		(duplicate_pad_numbers_are_jumpers no)
		(fp_line
			(start 0.508 -0.9398)
			(end -0.508 -0.9398)
			(stroke
				(width 0.1524)
				(type default)
			)
			(layer "F.SilkS")
		)
		(fp_line
			(start -0.508 -0.9398)
			(end -0.508 0.9398)
			(stroke
				(width 0.1524)
				(type default)
			)
			(layer "F.SilkS")
		)
		(fp_rect
			(start -0.508 0.9398)
			(end 0.508 -0.9398)
			(stroke
				(width 0)
				(type default)
			)
			(fill no)
			(layer "F.CrtYd")
		)
		(fp_rect
			(start -0.508 0.9398)
			(end 0.508 -0.9398)
			(stroke
				(width 0)
				(type default)
			)
			(fill no)
			(layer "F.Fab")
		)
		(pad "1" smd custom
			(at 0 -0.4445 180)
			(size 0.1397 0.1397)
			(layers "F.Cu" "F.Mask" "F.Paste")
			(net "P3V3_STBY_B")
			(options
				(clearance outline)
				(anchor circle)
			)
			(primitives
				(gr_poly
					(pts
						(arc
							(start -0.1778 -0.2794)
							(mid -0.249642 -0.249642)
							(end -0.2794 -0.1778)
						)
						(arc
							(start -0.2794 0.1778)
							(mid -0.249642 0.249642)
							(end -0.1778 0.2794)
						)
						(arc
							(start 0.1778 0.2794)
							(mid 0.249642 0.249642)
							(end 0.2794 0.1778)
						)
						(arc
							(start 0.2794 -0.1778)
							(mid 0.249642 -0.249642)
							(end 0.1778 -0.2794)
						)
					)
					(width 0)
					(fill yes)
				)
			)
		)
		(pad "2" smd custom
			(at 0 0.4445 180)
			(size 0.1397 0.1397)
			(layers "F.Cu" "F.Mask" "F.Paste")
			(net "HDD_PRSNT_17")
			(options
				(clearance outline)
				(anchor circle)
			)
			(primitives
				(gr_poly
					(pts
						(arc
							(start -0.1778 -0.2794)
							(mid -0.249642 -0.249642)
							(end -0.2794 -0.1778)
						)
						(arc
							(start -0.2794 0.1778)
							(mid -0.249642 0.249642)
							(end -0.1778 0.2794)
						)
						(arc
							(start 0.1778 0.2794)
							(mid 0.249642 0.249642)
							(end 0.2794 0.1778)
						)
						(arc
							(start 0.2794 -0.1778)
							(mid 0.249642 -0.249642)
							(end 0.1778 -0.2794)
						)
					)
					(width 0)
					(fill yes)
				)
			)
		)
	)
	(footprint ""
		(layer "F.Cu")
		(at 280.444448 -354.399342 -90)
		(property "Reference" "R1076"
			(at 0 0 270)
			(layer "F.SilkS")
			(hide yes)
			(effects
				(font
					(size 1.27 1.27)
				)
			)
		)
		(property "Value" "0R2J-2-GP"
			(at 0.064008 -3.993896 270)
			(unlocked yes)
			(layer "F.Fab")
			(hide yes)
			(effects
				(font
					(size 1.016 1.016)
					(thickness 0.1524)
				)
			)
		)
		(property "Device Type" "R402H16"
			(at 0.064008 -5.517896 270)
			(unlocked yes)
			(layer "F.Fab")
			(hide yes)
			(effects
				(font
					(size 1.016 1.016)
					(thickness 0.1524)
				)
			)
		)
		(duplicate_pad_numbers_are_jumpers no)
		(fp_line
			(start -0.508 -0.9398)
			(end -0.508 0.9398)
			(stroke
				(width 0.1524)
				(type default)
			)
			(layer "F.SilkS")
		)
		(fp_line
			(start 0.508 -0.9398)
			(end -0.508 -0.9398)
			(stroke
				(width 0.1524)
				(type default)
			)
			(layer "F.SilkS")
		)
		(fp_rect
			(start -0.508 0.9398)
			(end 0.508 -0.9398)
			(stroke
				(width 0)
				(type default)
			)
			(fill no)
			(layer "F.CrtYd")
		)
		(fp_rect
			(start -0.508 0.9398)
			(end 0.508 -0.9398)
			(stroke
				(width 0)
				(type default)
			)
			(fill no)
			(layer "F.Fab")
		)
		(pad "1" smd custom
			(at 0 -0.4445 270)
			(size 0.1397 0.1397)
			(layers "F.Cu" "F.Mask" "F.Paste")
			(net "MAX31790_B_SCL")
			(options
				(clearance outline)
				(anchor circle)
			)
			(primitives
				(gr_poly
					(pts
						(arc
							(start -0.1778 -0.2794)
							(mid -0.249642 -0.249642)
							(end -0.2794 -0.1778)
						)
						(arc
							(start -0.2794 0.1778)
							(mid -0.249642 0.249642)
							(end -0.1778 0.2794)
						)
						(arc
							(start 0.1778 0.2794)
							(mid 0.249642 0.249642)
							(end 0.2794 0.1778)
						)
						(arc
							(start 0.2794 -0.1778)
							(mid 0.249642 -0.249642)
							(end 0.1778 -0.2794)
						)
					)
					(width 0)
					(fill yes)
				)
			)
		)
		(pad "2" smd custom
			(at 0 0.4445 270)
			(size 0.1397 0.1397)
			(layers "F.Cu" "F.Mask" "F.Paste")
			(net "I2C_DPB_B_SCL_BUF")
			(options
				(clearance outline)
				(anchor circle)
			)
			(primitives
				(gr_poly
					(pts
						(arc
							(start -0.1778 -0.2794)
							(mid -0.249642 -0.249642)
							(end -0.2794 -0.1778)
						)
						(arc
							(start -0.2794 0.1778)
							(mid -0.249642 0.249642)
							(end -0.1778 0.2794)
						)
						(arc
							(start 0.1778 0.2794)
							(mid 0.249642 0.249642)
							(end 0.2794 0.1778)
						)
						(arc
							(start 0.2794 -0.1778)
							(mid 0.249642 -0.249642)
							(end 0.1778 -0.2794)
						)
					)
					(width 0)
					(fill yes)
				)
			)
		)
	)
	(footprint ""
		(layer "F.Cu")
		(at 27.298396 -370.9416 180)
		(property "Reference" "C710"
			(at 0 0 180)
			(layer "F.SilkS")
			(hide yes)
			(effects
				(font
					(size 1.27 1.27)
				)
			)
		)
		(property "Value" "SCD1U16V2KX-3GP"
			(at 1.1811 -2.7051 180)
			(unlocked yes)
			(layer "F.Fab")
			(hide yes)
			(effects
				(font
					(size 1.016 1.016)
					(thickness 0.1524)
				)
			)
		)
		(property "Device Type" "C402H22"
			(at 1.1811 -4.2291 180)
			(unlocked yes)
			(layer "F.Fab")
			(hide yes)
			(effects
				(font
					(size 1.016 1.016)
					(thickness 0.1524)
				)
			)
		)
		(duplicate_pad_numbers_are_jumpers no)
		(fp_rect
			(start -0.4318 0.9525)
			(end 0.4318 -0.9525)
			(stroke
				(width 0)
				(type default)
			)
			(fill no)
			(layer "F.CrtYd")
		)
		(fp_rect
			(start -0.4318 0.9525)
			(end 0.4318 -0.9525)
			(stroke
				(width 0)
				(type default)
			)
			(fill no)
			(layer "F.Fab")
		)
		(pad "1" smd custom
			(at 0 -0.4445 180)
			(size 0.1524 0.1524)
			(layers "F.Cu" "F.Mask" "F.Paste")
			(net "P3V3_IN")
			(options
				(clearance outline)
				(anchor circle)
			)
			(primitives
				(gr_poly
					(pts
						(arc
							(start 0.3048 -0.2032)
							(mid 0.275042 -0.275042)
							(end 0.2032 -0.3048)
						)
						(arc
							(start -0.2032 -0.3048)
							(mid -0.275042 -0.275042)
							(end -0.3048 -0.2032)
						)
						(arc
							(start -0.3048 0.2032)
							(mid -0.275042 0.275042)
							(end -0.2032 0.3048)
						)
						(arc
							(start 0.2032 0.3048)
							(mid 0.275042 0.275042)
							(end 0.3048 0.2032)
						)
					)
					(width 0)
					(fill yes)
				)
			)
		)
		(pad "2" smd custom
			(at 0 0.4445 180)
			(size 0.1524 0.1524)
			(layers "F.Cu" "F.Mask" "F.Paste")
			(net "GND")
			(options
				(clearance outline)
				(anchor circle)
			)
			(primitives
				(gr_poly
					(pts
						(arc
							(start 0.3048 -0.2032)
							(mid 0.275042 -0.275042)
							(end 0.2032 -0.3048)
						)
						(arc
							(start -0.2032 -0.3048)
							(mid -0.275042 -0.275042)
							(end -0.3048 -0.2032)
						)
						(arc
							(start -0.3048 0.2032)
							(mid -0.275042 0.275042)
							(end -0.2032 0.3048)
						)
						(arc
							(start 0.2032 0.3048)
							(mid 0.275042 0.275042)
							(end 0.3048 0.2032)
						)
					)
					(width 0)
					(fill yes)
				)
			)
		)
	)
)
